# T6G (Grand Teton) — schematic netlist excerpt (pin names and nets, part order shuffled) for the footprints in the layout excerpt that follows; sources: Cadence DE-HDL packaged netlist, KiCad conversion of 04192023_DAF0TMB3IC0_F0TG_MB_C_brd_V02_OCP.brd

PC299_4  Q_CAP  22UF 16V 20% X6S  pkg C0805  page 212 : A = SW_P12V_AUX_PVDDCR_CPU0_P1_FLT ; B = GND
C646  Q_CAP  10UF 6.3V 20% X6S  pkg C0402  page 290 : A = P0V9_CPU0_RT_2D ; B = GND
R6812  Q_RES  0 5% CHIP  pkg 0201LF  page 320 : A = SMB_RT_CPU1_P0_R_SCL ; B = SMB_RT_CPU1_P0_R2_SCL

(kicad_pcb
	(version 20260206)
	(generator "pcbnew")
	(generator_version "10.0")
	(general
		(thickness 1.6)
		(legacy_teardrops no)
	)
	(paper "A4")
	(title_block
		(title "04192023_DAF0TMB3IC0_F0TG_MB_C_brd_V02_OCP.brd")
		(comment 1 "Grand Teton / footprints 7738-7740 of 8354")
	)
	(layers
		(0 "F.Cu" signal "TOP")
		(4 "In1.Cu" signal "GND")
		(6 "In2.Cu" signal "IN1")
		(8 "In3.Cu" signal "GND1")
		(10 "In4.Cu" signal "IN2")
		(12 "In5.Cu" signal "GND2")
		(14 "In6.Cu" signal "IN3")
		(16 "In7.Cu" signal "GND3")
		(18 "In8.Cu" signal "VCC")
		(20 "In9.Cu" signal "VCC1")
		(22 "In10.Cu" signal "GND4")
		(24 "In11.Cu" signal "IN4")
		(26 "In12.Cu" signal "GND5")
		(28 "In13.Cu" signal "IN5")
		(30 "In14.Cu" signal "GND6")
		(32 "In15.Cu" signal "IN6")
		(34 "In16.Cu" signal "GND7")
		(2 "B.Cu" signal "BOTTOM")
		(9 "F.Adhes" user "F.Adhesive")
		(11 "B.Adhes" user "B.Adhesive")
		(13 "F.Paste" user "Package Geometry/Pastemask Top")
		(15 "B.Paste" user "Package Geometry/Pastemask Bottom")
		(5 "F.SilkS" user "Ref Des/Silkscreen Top")
		(7 "B.SilkS" user "Ref Des/Silkscreen Bottom")
		(1 "F.Mask" user "Board Geometry/Soldermask Top")
		(3 "B.Mask" user "Board Geometry/Soldermask Bottom")
		(17 "Dwgs.User" user "User.Drawings")
		(19 "Cmts.User" user "User.Comments")
		(21 "Eco1.User" user "User.Eco1")
		(23 "Eco2.User" user "User.Eco2")
		(25 "Edge.Cuts" user "Board Geometry/Outline")
		(27 "Margin" user)
		(31 "F.CrtYd" user "Package Geometry/Place Bound Top")
		(29 "B.CrtYd" user "Package Geometry/Place Bound Bottom")
		(35 "F.Fab" user "Ref Des/Assembly Top")
		(33 "B.Fab" user "Ref Des/Assembly Bottom")
	)
	(footprint ""
		(layer "B.Cu")
		(at 106.352848 -178.110134 -90)
		(property "Reference" "PC299_4"
			(at 0 0 90)
			(layer "B.SilkS")
			(hide yes)
			(effects
				(font
					(size 1.27 1.27)
				)
				(justify mirror)
			)
		)
		(property "Value" ""
			(at 0 0 90)
			(layer "B.Fab")
			(effects
				(font
					(size 1.27 1.27)
				)
				(justify mirror)
			)
		)
		(duplicate_pad_numbers_are_jumpers no)
		(fp_line
			(start -1.524 0.762)
			(end 1.524 0.762)
			(stroke
				(width 0.1524)
				(type default)
			)
			(layer "B.SilkS")
		)
		(fp_line
			(start 1.524 0.762)
			(end 1.524 -0.762)
			(stroke
				(width 0.1524)
				(type default)
			)
			(layer "B.SilkS")
		)
		(fp_line
			(start -1.524 -0.762)
			(end -1.524 0.762)
			(stroke
				(width 0.1524)
				(type default)
			)
			(layer "B.SilkS")
		)
		(fp_line
			(start 1.524 -0.762)
			(end -1.524 -0.762)
			(stroke
				(width 0.1524)
				(type default)
			)
			(layer "B.SilkS")
		)
		(fp_line
			(start -1.1049 0.724916)
			(end -1.1049 -0.724916)
			(stroke
				(width 0.1)
				(type default)
			)
			(layer "B.Fab")
		)
		(fp_line
			(start 1.1049 0.724916)
			(end -1.1049 0.724916)
			(stroke
				(width 0.1)
				(type default)
			)
			(layer "B.Fab")
		)
		(fp_line
			(start -1.1049 -0.724916)
			(end 1.1049 -0.724916)
			(stroke
				(width 0.1)
				(type default)
			)
			(layer "B.Fab")
		)
		(fp_line
			(start 1.1049 -0.724916)
			(end 1.1049 0.724916)
			(stroke
				(width 0.1)
				(type default)
			)
			(layer "B.Fab")
		)
		(pad "1" smd rect
			(at 0.889 0 270)
			(size 1.016 1.27)
			(layers "B.Cu" "B.Mask" "B.Paste")
			(net "SW_P12V_AUX_PVDDCR_CPU0_P1_FLT")
		)
		(pad "2" smd rect
			(at -0.889 0 270)
			(size 1.016 1.27)
			(layers "B.Cu" "B.Mask" "B.Paste")
			(net "GND")
		)
	)
	(footprint ""
		(layer "B.Cu")
		(at 343.118694 -398.942052 90)
		(property "Reference" "C646"
			(at 0 0 90)
			(layer "B.SilkS")
			(hide yes)
			(effects
				(font
					(size 1.27 1.27)
				)
				(justify mirror)
			)
		)
		(property "Value" ""
			(at 0 0 90)
			(layer "B.Fab")
			(effects
				(font
					(size 1.27 1.27)
				)
				(justify mirror)
			)
		)
		(duplicate_pad_numbers_are_jumpers no)
		(fp_line
			(start 0.7874 -0.4064)
			(end -0.7874 -0.4064)
			(stroke
				(width 0.1524)
				(type default)
			)
			(layer "B.SilkS")
		)
		(fp_line
			(start -0.7874 -0.4064)
			(end -0.7874 0.4064)
			(stroke
				(width 0.1524)
				(type default)
			)
			(layer "B.SilkS")
		)
		(fp_line
			(start 0.7874 0.4064)
			(end 0.7874 -0.4064)
			(stroke
				(width 0.1524)
				(type default)
			)
			(layer "B.SilkS")
		)
		(fp_line
			(start -0.7874 0.4064)
			(end 0.7874 0.4064)
			(stroke
				(width 0.1524)
				(type default)
			)
			(layer "B.SilkS")
		)
		(fp_line
			(start 0.67945 -0.305054)
			(end 0.12065 -0.305054)
			(stroke
				(width 0.1)
				(type default)
			)
			(layer "B.Fab")
		)
		(fp_line
			(start 0.12065 -0.305054)
			(end 0.12065 -0.2794)
			(stroke
				(width 0.1)
				(type default)
			)
			(layer "B.Fab")
		)
		(fp_line
			(start -0.12065 -0.3048)
			(end -0.67945 -0.3048)
			(stroke
				(width 0.1)
				(type default)
			)
			(layer "B.Fab")
		)
		(fp_line
			(start -0.67945 -0.3048)
			(end -0.67945 0.3048)
			(stroke
				(width 0.1)
				(type default)
			)
			(layer "B.Fab")
		)
		(fp_line
			(start 0.12065 -0.2794)
			(end -0.12065 -0.2794)
			(stroke
				(width 0.1)
				(type default)
			)
			(layer "B.Fab")
		)
		(fp_line
			(start -0.12065 -0.2794)
			(end -0.12065 -0.3048)
			(stroke
				(width 0.1)
				(type default)
			)
			(layer "B.Fab")
		)
		(fp_line
			(start 0.12065 0.2794)
			(end 0.12065 0.3048)
			(stroke
				(width 0.1)
				(type default)
			)
			(layer "B.Fab")
		)
		(fp_line
			(start -0.120396 0.2794)
			(end 0.12065 0.2794)
			(stroke
				(width 0.1)
				(type default)
			)
			(layer "B.Fab")
		)
		(fp_line
			(start 0.67945 0.3048)
			(end 0.67945 -0.305054)
			(stroke
				(width 0.1)
				(type default)
			)
			(layer "B.Fab")
		)
		(fp_line
			(start 0.12065 0.3048)
			(end 0.67945 0.3048)
			(stroke
				(width 0.1)
				(type default)
			)
			(layer "B.Fab")
		)
		(fp_line
			(start -0.120396 0.3048)
			(end -0.120396 0.2794)
			(stroke
				(width 0.1)
				(type default)
			)
			(layer "B.Fab")
		)
		(fp_line
			(start -0.67945 0.3048)
			(end -0.120396 0.3048)
			(stroke
				(width 0.1)
				(type default)
			)
			(layer "B.Fab")
		)
		(pad "1" smd circle
			(at 0.40005 0 270)
			(size 0 0)
			(layers "B.Cu" "B.Mask" "B.Paste")
			(net "P0V9_CPU0_RT_2D")
		)
		(pad "2" smd circle
			(at -0.40005 0 270)
			(size 0 0)
			(layers "B.Cu" "B.Mask" "B.Paste")
			(net "GND")
		)
	)
	(footprint ""
		(layer "B.Cu")
		(at 214.122 -335.026)
		(property "Reference" "R6812"
			(at 0 0 0)
			(layer "B.SilkS")
			(hide yes)
			(effects
				(font
					(size 1.27 1.27)
				)
				(justify mirror)
			)
		)
		(property "Value" ""
			(at 0 0 0)
			(layer "B.Fab")
			(effects
				(font
					(size 1.27 1.27)
				)
				(justify mirror)
			)
		)
		(duplicate_pad_numbers_are_jumpers no)
		(fp_line
			(start -0.32512 -0.175006)
			(end -0.32512 0.175006)
			(stroke
				(width 0.1)
				(type default)
			)
			(layer "B.Fab")
		)
		(fp_line
			(start -0.32512 0.175006)
			(end 0.32512 0.175006)
			(stroke
				(width 0.1)
				(type default)
			)
			(layer "B.Fab")
		)
		(fp_line
			(start 0.32512 -0.175006)
			(end -0.32512 -0.175006)
			(stroke
				(width 0.1)
				(type default)
			)
			(layer "B.Fab")
		)
		(fp_line
			(start 0.32512 0.175006)
			(end 0.32512 -0.175006)
			(stroke
				(width 0.1)
				(type default)
			)
			(layer "B.Fab")
		)
		(pad "1" smd rect
			(at 0.2667 0 180)
			(size 0.3048 0.381)
			(layers "B.Cu" "B.Mask" "B.Paste")
			(net "SMB_RT_CPU1_P0_R_SCL")
		)
		(pad "2" smd rect
			(at -0.2667 0)
			(size 0.3048 0.381)
			(layers "B.Cu" "B.Mask" "B.Paste")
			(net "SMB_RT_CPU1_P0_R2_SCL")
		)
	)
)
